M48
;Layer_Color=9474304
;FILE_FORMAT=4:4
METRIC,LZ
;TYPE=PLATED
T1F00S00C0.2540
T2F00S00C3.5000
%
T01
X00033Y00031
Y00038
X0003288Y00045166
X00033Y00051645
X00045Y00049
X00056Y00045
X00063Y00038
X00073
X0008Y00049
X00093Y00034
X00111Y00035
X00123
X00137Y00036
X00152
X00176Y00044
X00195873Y00044688
X00196187Y00051172
X00203458Y00048255
X00211Y0004787
Y0004
X00204114
X00193Y00037
X00187096Y00064
X00181031
X00203112Y00061996
X00212Y00061
X00211343Y00071
X00207794Y00079007
X002Y0007835
X00199Y0009
Y00101
X00198Y00117
Y00126
X00188Y00136
Y00148
Y0016
X0020221Y0015876
Y00174
X00208Y00193
X00206Y00215
X00205Y00239
X00206Y00259
Y00268
X0008791Y0026544
X0008029
X0007267
X0006505
X0004219
X0003457
X0003901Y00160198
X0005Y00161
X00039Y00147
X0004Y00114
X0005Y00115
X00069468Y00121045
X00102Y00119
X00106Y00106
X00117Y00121
X00125Y0013675
X00094
X00078Y00086
X00038Y00084
X00112Y00077
X00118Y00047
X00159Y00139375
Y001455
Y00152
X0020221Y0014352
X0001933
X0001171
X0001552Y0015114
X0001933Y0015876
X0001171
X0001552Y0016638
X0001933Y00174
X0001171
X0001552Y0018162
X0001933Y0018924
X0001171
X0001552Y0019686
X0001933Y0020448
X0001171
X0001552Y002121
X0001933Y0021972
X0001171
X0001552Y0022734
X0001933Y0023496
X0001171
X0001552Y0024258
X0001933Y002502
X0001171
X0001552Y0025782
X0001933Y0026544
X0002695
X0001171
X0001552Y001359
X0001933Y0012828
X0001171
X0001552Y0012066
X0001933Y0011304
X0001171
X0001552Y0010542
X0001933Y000978
X0001171
X0001552Y0009018
X0001933Y0008256
X0001171
X0001552Y0007494
X0001933Y0006732
X0001171
X0001552Y000597
X00015Y00050312
X00006826
X00006395Y00041971
X00012791Y00042
X0001552Y0027306
X0002314
X0002695Y0028068
X0001933
X0001171
X0001552Y002883
X0002314
X0002695Y0029592
X0001933
X0001171
X0001552Y0030354
X0002314
X0002695Y0031116
X0001933
X0001171
X0001552Y0031878
X0002314
X0002695Y003264
X0001933
X0001171
X0001552Y0033402
X0002314
X0001933Y0034164
X0001171
X0001552Y0034926
X0002314
X0001933Y0035688
X0001171
X0001552Y003645
X0002314
X00029145Y003658
X00028054Y00371915
X0001933Y0037212
X0001171
X0001552Y0037974
X00024523Y003775
X00023Y0038375
X00009Y00395
Y00408
X0003076Y0041022
X0003838
X0003457Y004026
X00033Y00393477
X00041
X00043782Y00379467
X0003982Y00373823
X00041962Y00367714
X0004981Y0037212
X0005743
X0006505
X0007267
X0008029
X0008791
X0009553
X0010315
X0011077
X0010696Y0037974
X0009934
X0009172
X000841
X0007648
X0006886
X0006124
X0005362
X0006505Y0038736
X0007267
X0008029
X0008791
X0009553
X000841Y0039498
X0007648
X0006886
X00062Y00394
X0006505Y004026
X0007267
X0008029
X0007648Y0041022
X0006886
X00079Y0036
X000841Y003645
X0009172
X0009934
X0010696
X0010315Y0034164
X0009553
X0008791
X000841Y0033402
X0007648
X0006886
X0006124
X0006505Y003264
X0007267
X0008029
X0008791
X00083Y00317
X0007648Y0031878
X0006886
X00064425Y00314602
X00055998Y00314097
X0005458Y00320095
X0005743Y003264
X00050238Y003258
X00047228Y00332057
X00046887Y00338234
X00046651Y00344528
X00046267Y00350969
X00031485Y00353188
X00031719Y00347
X00032151Y0033981
X00031576Y003328
X00035076Y003268
X00038651Y00320417
X00036Y00314802
X00043408Y00314602
X0003076Y0031878
Y0030354
Y002883
X0003457Y0028068
X0004219
X0004981
X0005743
X0006886Y0027306
X0007648
X000841
X0009172
X0009553Y0028068
X0008791
X0008029
X0009172Y002883
X0009553Y0029592
X0009172Y0030354
X0009553Y0031116
X00095Y00334
X00126466Y00319
X0013253
X00159Y00322
X00177Y0034
X0019Y00354
X00181Y00375
X0017935Y0038736
X0018697
X0019459
X0020221
X0020983
X0021364Y0039498
X0020602
X001984
X0019078
X0018316
X0017554
X0016792
X001603
X0015268
X0014506
X0013744
X0014125Y004026
X0014887
X0015649
X0016411
X0017173
X0017935
X0018697
X0019459
X0020221
X0020983
X0021364Y0041022
X0020602
X001984
X0019078
X0018316
X0017554
X0016792
X001603
X0015268
X0014506
X0014887Y0038736
X0015649
X0016411
X0017173
X0014125
X0013363
X0012601
X00135Y00368
X00145
X00030909Y003598
X0003076Y0027306
X0003838
X00046
X00206Y00276
T02
X0011Y0042
M30
